# S9S_MB_2U (Grand Teton) — schematic netlist excerpt (pin names and nets, part order shuffled) for the footprints in the layout excerpt that follows; sources: Cadence DE-HDL packaged netlist, KiCad conversion of 03242023_DA0F0TMBIJ0_F0T_Motherboard_J_brd_V01_OCP.brd

J21  SCONN288_ADR50017P130CC  SCONN288_ADR50017-P130CC IO  pkg DDR288S_1-1VXB  page 102
  VIN_BULK0  = P12V_S3_AUX_CPU1_NVDIMM
  RFU0  = TP_CHC_CPU1_DIMM1_FRU_0
  VIN_MGMT  = P3V3_AUX
  HSCL  = I3C_SPD_DDRABCD_CPU1_LVC1_SCL_4
  HSDA  = I3C_SPD_DDRABCD_CPU1_LVC1_SDA
  VSS0  = GND
  DQ0_A  = M_C_CPU1_SA_DQ<0>
  VSS1  = GND
  DQ1_A  = M_C_CPU1_SA_DQ<1>
  VSS2  = GND
  DQS0_A_T  = M_C_CPU1_SA_DQS_DP<0>
  DQS0_A_C  = M_C_CPU1_SA_DQS_DN<0>
  VSS3  = GND
  DQ4_A  = M_C_CPU1_SA_DQ<4>
  VSS4  = GND
  DQ5_A  = M_C_CPU1_SA_DQ<5>
  VSS5  = GND
  DQ8_A  = M_C_CPU1_SA_DQ<8>
  VSS6  = GND
  DQ9_A  = M_C_CPU1_SA_DQ<9>
  VSS7  = GND
  DQS1_A_T  = M_C_CPU1_SA_DQS_DP<1>
  DQS1_A_C  = M_C_CPU1_SA_DQS_DN<1>
  VSS8  = GND
  DQ12_A  = M_C_CPU1_SA_DQ<12>
  VSS9  = GND
  DQ13_A  = M_C_CPU1_SA_DQ<13>
  VSS10  = GND
  DQ16_A  = M_C_CPU1_SA_DQ<16>
  VSS11  = GND
  DQ17_A  = M_C_CPU1_SA_DQ<17>
  VSS12  = GND
  DQS2_A_T  = M_C_CPU1_SA_DQS_DP<2>
  DQS2_A_C  = M_C_CPU1_SA_DQS_DN<2>
  VSS13  = GND
  DQ20_A  = M_C_CPU1_SA_DQ<20>
  VSS14  = GND
  DQ21_A  = M_C_CPU1_SA_DQ<21>
  VSS15  = GND
  DQ24_A  = M_C_CPU1_SA_DQ<24>
  VSS16  = GND
  DQ25_A  = M_C_CPU1_SA_DQ<25>
  VSS17  = GND
  DQS3_A_T  = M_C_CPU1_SA_DQS_DP<3>
  DQS3_A_C  = M_C_CPU1_SA_DQS_DN<3>
  VSS18  = GND
  DQ28_A  = M_C_CPU1_SA_DQ<28>
  VSS19  = GND
  DQ29_A  = M_C_CPU1_SA_DQ<29>
  VSS20  = GND
  CB0_A  = M_C_CPU1_SA_CB<0>
  VSS21  = GND
  CB1_A  = M_C_CPU1_SA_CB<1>
  VSS22  = GND
  DQS4_A_T  = M_C_CPU1_SA_DQS_DP<4>
  DQS4_A_C  = M_C_CPU1_SA_DQS_DN<4>
  VSS23  = GND
  CB4_A  = M_C_CPU1_SA_CB<4>
  VSS24  = GND
  CB5_A  = M_C_CPU1_SA_CB<5>
  VSS25  = GND
  ALERT_N  = M_C_CPU1_ALERT_N
  VSS26  = GND
  CS0_A_N  = M_C_CPU1_SA_CS_N<0>
  VSS27  = GND
  CA0_A  = M_C_CPU1_SA_CA<0>
  VSS28  = GND
  CA2_A  = M_C_CPU1_SA_CA<2>
  VSS29  = GND
  CA4_A  = M_C_CPU1_SA_CA<4>
  VSS30  = GND
  CA6_A  = M_C_CPU1_SA_CA<6>
  VSS31  = GND
  PAR_A  = M_C_CPU1_SA_PAR
  VSS32  = GND
  CA0_B  = M_C_CPU1_SB_CA<0>
  VSS33  = GND
  CA2_B  = M_C_CPU1_SB_CA<2>
  VSS34  = GND
  CA4_B  = M_C_CPU1_SB_CA<4>
  VSS35  = GND
  CA6_B  = M_C_CPU1_SB_CA<6>
  VSS36  = GND
  CS0_B_N  = M_C_CPU1_SB_CS_N<0>
  VSS37  = GND
  \lbd||rsp_a_n\  = M_C_CPU1_SA_RSP<0>
  \lbs||rsp_b_n\  = M_C_CPU1_SB_RSP<0>
  VSS38  = GND
  CB4_B  = M_C_CPU1_SB_CB<4>
  VSS39  = GND
  CB5_B  = M_C_CPU1_SB_CB<5>
  VSS40  = GND
  \dqs9_b_t||tdqs9_b_t||dbi4_b_n\  = M_C_CPU1_SB_DQS_DP<9>
  \dqs9_b_c||tdqs9_b_c\  = M_C_CPU1_SB_DQS_DN<9>
  VSS41  = GND
  CB0_B  = M_C_CPU1_SB_CB<0>
  VSS42  = GND
  CB1_B  = M_C_CPU1_SB_CB<1>
  VSS43  = GND
  DQ0_B  = M_C_CPU1_SB_DQ<0>
  VSS44  = GND
  DQ1_B  = M_C_CPU1_SB_DQ<1>
  VSS45  = GND
  DQS0_B_T  = M_C_CPU1_SB_DQS_DP<0>
  DQS0_B_C  = M_C_CPU1_SB_DQS_DN<0>
  VSS46  = GND
  DQ4_B  = M_C_CPU1_SB_DQ<4>
  VSS47  = GND
  DQ5_B  = M_C_CPU1_SB_DQ<5>
  VSS48  = GND
  DQ8_B  = M_C_CPU1_SB_DQ<8>
  VSS49  = GND
  DQ9_B  = M_C_CPU1_SB_DQ<9>
  VSS50  = GND
  DQS1_B_T  = M_C_CPU1_SB_DQS_DP<1>
  DQS1_B_C  = M_C_CPU1_SB_DQS_DN<1>
  VSS51  = GND
  DQ12_B  = M_C_CPU1_SB_DQ<12>
  VSS52  = GND
  DQ13_B  = M_C_CPU1_SB_DQ<13>
  VSS53  = GND
  DQ16_B  = M_C_CPU1_SB_DQ<16>
  VSS54  = GND
  DQ17_B  = M_C_CPU1_SB_DQ<17>
  VSS55  = GND
  DQS2_B_T  = M_C_CPU1_SB_DQS_DP<2>
  DQS2_B_C  = M_C_CPU1_SB_DQS_DN<2>
  VSS56  = GND
  DQ20_B  = M_C_CPU1_SB_DQ<20>
  VSS57  = GND
  DQ21_B  = M_C_CPU1_SB_DQ<21>
  VSS58  = GND
  DQ24_B  = M_C_CPU1_SB_DQ<24>
  VSS59  = GND
  DQ25_B  = M_C_CPU1_SB_DQ<25>
  VSS60  = GND
  DQS3_B_T  = M_C_CPU1_SB_DQS_DP<3>
  DQS3_B_C  = M_C_CPU1_SB_DQS_DN<3>
  VSS61  = GND
  DQ28_B  = M_C_CPU1_SB_DQ<28>
  VSS62  = GND
  DQ29_B  = M_C_CPU1_SB_DQ<29>
  VSS63  = GND
  RFU1  = TP_CHC_CPU1_DIMM1_FRU_1
  VIN_BULK1  = P12V_S3_AUX_CPU1_NVDIMM
  VIN_BULK2  = P12V_S3_AUX_CPU1_NVDIMM
  \pwr_good||fail_n\  = PWRGD_CHC_CPU1_DIMM1
  HSA  = PD_CHC_CPU1_DIMM1_SAA
  RFU2  = TP_CHC_CPU1_DIMM1_FRU_2
  RFU3  = TP_CHC_CPU1_DIMM1_FRU_3
  VSS64  = GND
  DQ2_A  = M_C_CPU1_SA_DQ<2>
  VSS65  = GND
  DQ3_A  = M_C_CPU1_SA_DQ<3>
  VSS66  = GND
  \dqs5_a_c||tdqs5_a_c||dqs5_a_t||tdqs5_a_t\  = M_C_CPU1_SA_DQS_DN<5>
  \dqs5_a_t||tdqs5_a_t\  = M_C_CPU1_SA_DQS_DP<5>
  VSS67  = GND
  DQ6_A  = M_C_CPU1_SA_DQ<6>
  VSS68  = GND
  DQ7_A  = M_C_CPU1_SA_DQ<7>
  VSS69  = GND
  DQ10_A  = M_C_CPU1_SA_DQ<10>
  VSS70  = GND
  DQ11_A  = M_C_CPU1_SA_DQ<11>
  VSS71  = GND
  \dqs6_a_c||tdqs6_a_c||dqs6_a_t||tdqs6_a_t\  = M_C_CPU1_SA_DQS_DN<6>
  \dqs6_a_t||tdqs6_a_t\  = M_C_CPU1_SA_DQS_DP<6>
  VSS72  = GND
  DQ14_A  = M_C_CPU1_SA_DQ<14>
  VSS73  = GND
  DQ15_A  = M_C_CPU1_SA_DQ<15>
  VSS74  = GND
  DQ18_A  = M_C_CPU1_SA_DQ<18>
  VSS75  = GND
  DQ19_A  = M_C_CPU1_SA_DQ<19>
  VSS76  = GND
  \dqs7_a_c||tdqs7_a_c\  = M_C_CPU1_SA_DQS_DN<7>
  \dqs7_a_t||tdqs7_a_t\  = M_C_CPU1_SA_DQS_DP<7>
  VSS77  = GND
  DQ22_A  = M_C_CPU1_SA_DQ<22>
  VSS78  = GND
  DQ23_A  = M_C_CPU1_SA_DQ<23>
  VSS79  = GND
  DQ26_A  = M_C_CPU1_SA_DQ<26>
  VSS80  = GND
  DQ27_A  = M_C_CPU1_SA_DQ<27>
  VSS81  = GND
  \dqs8_a_c||tdqs8_a_c\  = M_C_CPU1_SA_DQS_DN<8>
  \dqs8_a_t||tdqs8_a_t\  = M_C_CPU1_SA_DQS_DP<8>
  VSS82  = GND
  DQ30_A  = M_C_CPU1_SA_DQ<30>
  VSS83  = GND
  DQ31_A  = M_C_CPU1_SA_DQ<31>
  VSS84  = GND
  CB2_A  = M_C_CPU1_SA_CB<2>
  VSS85  = GND
  CB3_A  = M_C_CPU1_SA_CB<3>
  VSS86  = GND
  \dqs9_a_c||tdqs9_a_c\  = M_C_CPU1_SA_DQS_DN<9>
  \dqs9_a_t||tdqs9_a_t\  = M_C_CPU1_SA_DQS_DP<9>
  VSS87  = GND
  CB6_A  = M_C_CPU1_SA_CB<6>
  VSS88  = GND
  CB7_A  = M_C_CPU1_SA_CB<7>
  VSS89  = GND
  RESET_N  = RST_M_CD_CPU1_FPGA_N
  VSS90  = GND
  CS1_A_N  = M_C_CPU1_SA_CS_N<1>
  VSS91  = GND
  CA1_A  = M_C_CPU1_SA_CA<1>
  VSS92  = GND
  CA3_A  = M_C_CPU1_SA_CA<3>
  VSS93  = GND
  CA5_A  = M_C_CPU1_SA_CA<5>
  VSS94  = GND
  CK_T  = M_C_CPU1_CLK_DP<0>
  CK_C  = M_C_CPU1_CLK_DN<0>
  VSS95  = GND
  RFU4  = TP_CHC_CPU1_DIMM1_FRU_4
  CA1_B  = M_C_CPU1_SB_CA<1>
  VSS96  = GND
  CA3_B  = M_C_CPU1_SB_CA<3>
  VSS97  = GND
  CA5_B  = M_C_CPU1_SB_CA<5>
  VSS98  = GND
  PAR_B  = M_C_CPU1_SB_PAR
  VSS99  = GND
  CS1_B_N  = M_C_CPU1_SB_CS_N<1>
  VSS100  = GND
  RFU5  = TP_CHC_CPU1_DIMM1_FRU_5
  RFU6  = TP_CHC_CPU1_DIMM1_FRU_6
  VSS101  = GND
  CB6_B  = M_C_CPU1_SB_CB<6>
  VSS102  = GND
  CB7_B  = M_C_CPU1_SB_CB<7>
  VSS103  = GND
  DQS4_B_C  = M_C_CPU1_SB_DQS_DN<4>
  DQS4_B_T  = M_C_CPU1_SB_DQS_DP<4>
  VSS104  = GND
  CB2_B  = M_C_CPU1_SB_CB<2>
  VSS105  = GND
  CB3_B  = M_C_CPU1_SB_CB<3>
  VSS106  = GND
  DQ2_B  = M_C_CPU1_SB_DQ<2>
  VSS107  = GND
  DQ3_B  = M_C_CPU1_SB_DQ<3>
  VSS108  = GND
  \dqs5_b_c||tdqs5_b_c\  = M_C_CPU1_SB_DQS_DN<5>
  \dqs5_b_t||tdqs5_b_t\  = M_C_CPU1_SB_DQS_DP<5>
  VSS109  = GND
  DQ6_B  = M_C_CPU1_SB_DQ<6>
  VSS110  = GND
  DQ7_B  = M_C_CPU1_SB_DQ<7>
  VSS111  = GND
  DQ10_B  = M_C_CPU1_SB_DQ<10>
  VSS112  = GND
  DQ11_B  = M_C_CPU1_SB_DQ<11>
  VSS113  = GND
  \dqs6_b_c||tdqs6_b_c\  = M_C_CPU1_SB_DQS_DN<6>
  \dqs6_b_t||tdqs6_b_t\  = M_C_CPU1_SB_DQS_DP<6>
  VSS114  = GND
  DQ14_B  = M_C_CPU1_SB_DQ<14>
  VSS115  = GND
  DQ15_B  = M_C_CPU1_SB_DQ<15>
  VSS116  = GND
  DQ18_B  = M_C_CPU1_SB_DQ<18>
  VSS117  = GND
  DQ19_B  = M_C_CPU1_SB_DQ<19>
  VSS118  = GND
  \dqs7_b_c||tdqs7_b_c\  = M_C_CPU1_SB_DQS_DN<7>
  \dqs7_b_t||tdqs7_b_t\  = M_C_CPU1_SB_DQS_DP<7>
  VSS119  = GND
  DQ22_B  = M_C_CPU1_SB_DQ<22>
  VSS120  = GND
  DQ23_B  = M_C_CPU1_SB_DQ<23>
  VSS121  = GND
  DQ26_B  = M_C_CPU1_SB_DQ<26>
  VSS122  = GND
  DQ27_B  = M_C_CPU1_SB_DQ<27>
  VSS123  = GND
  \dqs8_b_c||tdqs8_b_c\  = M_C_CPU1_SB_DQS_DN<8>
  \dqs8_b_t||tdqs8_b_t\  = M_C_CPU1_SB_DQS_DP<8>
  VSS124  = GND
  DQ30_B  = M_C_CPU1_SB_DQ<30>
  VSS125  = GND
  DQ31_B  = M_C_CPU1_SB_DQ<31>
  VSS126  = GND
  G1  = GND
  G2  = GND
  G3  = GND

(kicad_pcb
	(version 20260206)
	(generator "pcbnew")
	(generator_version "10.0")
	(general
		(thickness 1.6)
		(legacy_teardrops no)
	)
	(paper "A4")
	(title_block
		(title "03242023_DA0F0TMBIJ0_F0T_Motherboard_J_brd_V01_OCP.brd")
		(comment 1 "Grand Teton / footprint 663 of 6105 (J21), pads 183-228 of 291")
	)
	(layers
		(0 "F.Cu" signal "TOP")
		(4 "In1.Cu" signal "GND")
		(6 "In2.Cu" signal "IN1")
		(8 "In3.Cu" signal "GND1")
		(10 "In4.Cu" signal "IN2")
		(12 "In5.Cu" signal "GND2")
		(14 "In6.Cu" signal "IN3")
		(16 "In7.Cu" signal "GND3")
		(18 "In8.Cu" signal "VCC")
		(20 "In9.Cu" signal "VCC1")
		(22 "In10.Cu" signal "GND4")
		(24 "In11.Cu" signal "IN4")
		(26 "In12.Cu" signal "GND5")
		(28 "In13.Cu" signal "IN5")
		(30 "In14.Cu" signal "GND6")
		(32 "In15.Cu" signal "IN6")
		(34 "In16.Cu" signal "GND7")
		(2 "B.Cu" signal "BOTTOM")
		(9 "F.Adhes" user "F.Adhesive")
		(11 "B.Adhes" user "B.Adhesive")
		(13 "F.Paste" user "Package Geometry/Pastemask Top")
		(15 "B.Paste" user "Package Geometry/Pastemask Bottom")
		(5 "F.SilkS" user "Ref Des/Silkscreen Top")
		(7 "B.SilkS" user "Ref Des/Silkscreen Bottom")
		(1 "F.Mask" user "Board Geometry/Soldermask Top")
		(3 "B.Mask" user "Board Geometry/Soldermask Bottom")
		(17 "Dwgs.User" user "User.Drawings")
		(19 "Cmts.User" user "User.Comments")
		(21 "Eco1.User" user "User.Eco1")
		(23 "Eco2.User" user "User.Eco2")
		(25 "Edge.Cuts" user "Board Geometry/Outline")
		(27 "Margin" user)
		(31 "F.CrtYd" user "Package Geometry/Place Bound Top")
		(29 "B.CrtYd" user "Package Geometry/Place Bound Bottom")
		(35 "F.Fab" user "Ref Des/Assembly Top")
		(33 "B.Fab" user "Ref Des/Assembly Bottom")
	)
	(footprint ""
		(layer "F.Cu")
		(at 25.27808 -258.091686)
		(property "Reference" "J21"
			(at -0.325882 -81.821274 0)
			(unlocked yes)
			(layer "F.SilkS")
			(effects
				(font
					(size 0.7874 0.5842)
					(thickness 0.1524)
				)
				(justify left)
			)
		)
		(property "Value" ""
			(at 0 0 0)
			(layer "F.Fab")
			(effects
				(font
					(size 1.27 1.27)
				)
			)
		)
		(duplicate_pad_numbers_are_jumpers no)
		(pad "183" smd rect
			(at 2.050034 -31.025084 270)
			(size 0.519938 1.4986)
			(layers "F.Cu" "F.Mask" "F.Paste")
			(net "M_C_CPU1_SA_DQ<23>")
		)
		(pad "184" smd rect
			(at 2.050034 -30.174946 270)
			(size 0.519938 1.4986)
			(layers "F.Cu" "F.Mask" "F.Paste")
			(net "GND")
		)
		(pad "185" smd rect
			(at 2.050034 -29.325062 270)
			(size 0.519938 1.4986)
			(layers "F.Cu" "F.Mask" "F.Paste")
			(net "M_C_CPU1_SA_DQ<26>")
		)
		(pad "186" smd rect
			(at 2.050034 -28.474924 270)
			(size 0.519938 1.4986)
			(layers "F.Cu" "F.Mask" "F.Paste")
			(net "GND")
		)
		(pad "187" smd rect
			(at 2.050034 -27.62504 270)
			(size 0.519938 1.4986)
			(layers "F.Cu" "F.Mask" "F.Paste")
			(net "M_C_CPU1_SA_DQ<27>")
		)
		(pad "188" smd rect
			(at 2.050034 -26.774902 270)
			(size 0.519938 1.4986)
			(layers "F.Cu" "F.Mask" "F.Paste")
			(net "GND")
		)
		(pad "189" smd rect
			(at 2.050034 -25.925018 270)
			(size 0.519938 1.4986)
			(layers "F.Cu" "F.Mask" "F.Paste")
			(net "M_C_CPU1_SA_DQS_DN<8>")
		)
		(pad "190" smd rect
			(at 2.050034 -25.07488 270)
			(size 0.519938 1.4986)
			(layers "F.Cu" "F.Mask" "F.Paste")
			(net "M_C_CPU1_SA_DQS_DP<8>")
		)
		(pad "191" smd rect
			(at 2.050034 -24.224996 270)
			(size 0.519938 1.4986)
			(layers "F.Cu" "F.Mask" "F.Paste")
			(net "GND")
		)
		(pad "192" smd rect
			(at 2.050034 -23.375112 270)
			(size 0.519938 1.4986)
			(layers "F.Cu" "F.Mask" "F.Paste")
			(net "M_C_CPU1_SA_DQ<30>")
		)
		(pad "193" smd rect
			(at 2.050034 -22.524974 270)
			(size 0.519938 1.4986)
			(layers "F.Cu" "F.Mask" "F.Paste")
			(net "GND")
		)
		(pad "194" smd rect
			(at 2.050034 -21.67509 270)
			(size 0.519938 1.4986)
			(layers "F.Cu" "F.Mask" "F.Paste")
			(net "M_C_CPU1_SA_DQ<31>")
		)
		(pad "195" smd rect
			(at 2.050034 -20.824952 270)
			(size 0.519938 1.4986)
			(layers "F.Cu" "F.Mask" "F.Paste")
			(net "GND")
		)
		(pad "196" smd rect
			(at 2.050034 -19.975068 270)
			(size 0.519938 1.4986)
			(layers "F.Cu" "F.Mask" "F.Paste")
			(net "M_C_CPU1_SA_CB<2>")
		)
		(pad "197" smd rect
			(at 2.050034 -19.12493 270)
			(size 0.519938 1.4986)
			(layers "F.Cu" "F.Mask" "F.Paste")
			(net "GND")
		)
		(pad "198" smd rect
			(at 2.050034 -18.275046 270)
			(size 0.519938 1.4986)
			(layers "F.Cu" "F.Mask" "F.Paste")
			(net "M_C_CPU1_SA_CB<3>")
		)
		(pad "199" smd rect
			(at 2.050034 -17.424908 270)
			(size 0.519938 1.4986)
			(layers "F.Cu" "F.Mask" "F.Paste")
			(net "GND")
		)
		(pad "200" smd rect
			(at 2.050034 -16.575024 270)
			(size 0.519938 1.4986)
			(layers "F.Cu" "F.Mask" "F.Paste")
			(net "M_C_CPU1_SA_DQS_DN<9>")
		)
		(pad "201" smd rect
			(at 2.050034 -15.724886 270)
			(size 0.519938 1.4986)
			(layers "F.Cu" "F.Mask" "F.Paste")
			(net "M_C_CPU1_SA_DQS_DP<9>")
		)
		(pad "202" smd rect
			(at 2.050034 -14.875002 270)
			(size 0.519938 1.4986)
			(layers "F.Cu" "F.Mask" "F.Paste")
			(net "GND")
		)
		(pad "203" smd rect
			(at 2.050034 -14.025118 270)
			(size 0.519938 1.4986)
			(layers "F.Cu" "F.Mask" "F.Paste")
			(net "M_C_CPU1_SA_CB<6>")
		)
		(pad "204" smd rect
			(at 2.050034 -13.17498 270)
			(size 0.519938 1.4986)
			(layers "F.Cu" "F.Mask" "F.Paste")
			(net "GND")
		)
		(pad "205" smd rect
			(at 2.050034 -12.325096 270)
			(size 0.519938 1.4986)
			(layers "F.Cu" "F.Mask" "F.Paste")
			(net "M_C_CPU1_SA_CB<7>")
		)
		(pad "206" smd rect
			(at 2.050034 -11.474958 270)
			(size 0.519938 1.4986)
			(layers "F.Cu" "F.Mask" "F.Paste")
			(net "GND")
		)
		(pad "207" smd rect
			(at 2.050034 -10.625074 270)
			(size 0.519938 1.4986)
			(layers "F.Cu" "F.Mask" "F.Paste")
			(net "RST_M_CD_CPU1_FPGA_N")
		)
		(pad "208" smd rect
			(at 2.050034 -9.774936 270)
			(size 0.519938 1.4986)
			(layers "F.Cu" "F.Mask" "F.Paste")
			(net "GND")
		)
		(pad "209" smd rect
			(at 2.050034 -8.925052 270)
			(size 0.519938 1.4986)
			(layers "F.Cu" "F.Mask" "F.Paste")
			(net "M_C_CPU1_SA_CS_N<1>")
		)
		(pad "210" smd rect
			(at 2.050034 -8.074914 270)
			(size 0.519938 1.4986)
			(layers "F.Cu" "F.Mask" "F.Paste")
			(net "GND")
		)
		(pad "211" smd rect
			(at 2.050034 -7.22503 270)
			(size 0.519938 1.4986)
			(layers "F.Cu" "F.Mask" "F.Paste")
			(net "M_C_CPU1_SA_CA<1>")
		)
		(pad "212" smd rect
			(at 2.050034 -6.374892 270)
			(size 0.519938 1.4986)
			(layers "F.Cu" "F.Mask" "F.Paste")
			(net "GND")
		)
		(pad "213" smd rect
			(at 2.050034 -5.525008 270)
			(size 0.519938 1.4986)
			(layers "F.Cu" "F.Mask" "F.Paste")
			(net "M_C_CPU1_SA_CA<3>")
		)
		(pad "214" smd rect
			(at 2.050034 -4.675124 270)
			(size 0.519938 1.4986)
			(layers "F.Cu" "F.Mask" "F.Paste")
			(net "GND")
		)
		(pad "215" smd rect
			(at 2.050034 -3.824986 270)
			(size 0.519938 1.4986)
			(layers "F.Cu" "F.Mask" "F.Paste")
			(net "M_C_CPU1_SA_CA<5>")
		)
		(pad "216" smd rect
			(at 2.050034 -2.975102 270)
			(size 0.519938 1.4986)
			(layers "F.Cu" "F.Mask" "F.Paste")
			(net "GND")
		)
		(pad "217" smd rect
			(at 2.050034 -2.124964 270)
			(size 0.519938 1.4986)
			(layers "F.Cu" "F.Mask" "F.Paste")
			(net "M_C_CPU1_CLK_DP<0>")
		)
		(pad "218" smd rect
			(at 2.050034 -1.27508 270)
			(size 0.519938 1.4986)
			(layers "F.Cu" "F.Mask" "F.Paste")
			(net "M_C_CPU1_CLK_DN<0>")
		)
		(pad "219" smd rect
			(at 2.050034 -0.424942 270)
			(size 0.519938 1.4986)
			(layers "F.Cu" "F.Mask" "F.Paste")
			(net "GND")
		)
		(pad "220" smd rect
			(at 2.050034 5.525008 270)
			(size 0.519938 1.4986)
			(layers "F.Cu" "F.Mask" "F.Paste")
			(net "TP_CHC_CPU1_DIMM1_FRU_4")
		)
		(pad "221" smd rect
			(at 2.050034 6.374892 270)
			(size 0.519938 1.4986)
			(layers "F.Cu" "F.Mask" "F.Paste")
			(net "M_C_CPU1_SB_CA<1>")
		)
		(pad "222" smd rect
			(at 2.050034 7.22503 270)
			(size 0.519938 1.4986)
			(layers "F.Cu" "F.Mask" "F.Paste")
			(net "GND")
		)
		(pad "223" smd rect
			(at 2.050034 8.074914 270)
			(size 0.519938 1.4986)
			(layers "F.Cu" "F.Mask" "F.Paste")
			(net "M_C_CPU1_SB_CA<3>")
		)
		(pad "224" smd rect
			(at 2.050034 8.925052 270)
			(size 0.519938 1.4986)
			(layers "F.Cu" "F.Mask" "F.Paste")
			(net "GND")
		)
		(pad "225" smd rect
			(at 2.050034 9.774936 270)
			(size 0.519938 1.4986)
			(layers "F.Cu" "F.Mask" "F.Paste")
			(net "M_C_CPU1_SB_CA<5>")
		)
		(pad "226" smd rect
			(at 2.050034 10.625074 270)
			(size 0.519938 1.4986)
			(layers "F.Cu" "F.Mask" "F.Paste")
			(net "GND")
		)
		(pad "227" smd rect
			(at 2.050034 11.474958 270)
			(size 0.519938 1.4986)
			(layers "F.Cu" "F.Mask" "F.Paste")
			(net "M_C_CPU1_SB_PAR")
		)
		(pad "228" smd rect
			(at 2.050034 12.325096 270)
			(size 0.519938 1.4986)
			(layers "F.Cu" "F.Mask" "F.Paste")
			(net "GND")
		)
	)
)
